# BASEBOARD_FAB2 (Tioga Pass) — schematic netlist excerpt (pin names and nets, part order shuffled) for the footprints in the layout excerpt that follows; sources: Cadence DE-HDL packaged netlist, KiCad conversion of Wiwynn_Tioga_Pass_MB.brd

R2U11  RES  665 1.0% CHIP  pkg 0402  page 138 : A = P3V3_STBY ; B = SMB_LAN_STBY_LVC3_SDA
C2A1  CAP_A  47UF 4V 20% X5R  pkg 0603V  page 228 : A = PVDDQ_KLM ; B = GND
R4D2  RES  27.4 1% CHIP  pkg 0402  page 103 : A = CLK_100M_CPU1_BCLK1_R_DP ; B = CLK_100M_CPU1_BCLK1_DP

(kicad_pcb
	(version 20260206)
	(generator "pcbnew")
	(generator_version "10.0")
	(general
		(thickness 1.6)
		(legacy_teardrops no)
	)
	(paper "A4")
	(title_block
		(title "Wiwynn_Tioga_Pass_MB.brd")
		(comment 1 "Tioga Pass / footprints 584-586 of 4770")
	)
	(layers
		(0 "F.Cu" signal "TOP")
		(4 "In1.Cu" signal "L2GND")
		(6 "In2.Cu" signal "L3")
		(8 "In3.Cu" signal "L4GND")
		(10 "In4.Cu" signal "L5")
		(12 "In5.Cu" signal "L6GND")
		(14 "In6.Cu" signal "L7VCC")
		(16 "In7.Cu" signal "L8VCC")
		(18 "In8.Cu" signal "L9GND")
		(20 "In9.Cu" signal "L10")
		(22 "In10.Cu" signal "L11GND")
		(24 "In11.Cu" signal "L12")
		(26 "In12.Cu" signal "L13GND")
		(2 "B.Cu" signal "BOTTOM")
		(9 "F.Adhes" user "F.Adhesive")
		(11 "B.Adhes" user "B.Adhesive")
		(13 "F.Paste" user "Package Geometry/Pastemask Top")
		(15 "B.Paste" user "Package Geometry/Pastemask Bottom")
		(5 "F.SilkS" user "Ref Des/Silkscreen Top")
		(7 "B.SilkS" user "Ref Des/Silkscreen Bottom")
		(1 "F.Mask" user "Board Geometry/Soldermask Top")
		(3 "B.Mask" user "Board Geometry/Soldermask Bottom")
		(17 "Dwgs.User" user "User.Drawings")
		(19 "Cmts.User" user "User.Comments")
		(21 "Eco1.User" user "User.Eco1")
		(23 "Eco2.User" user "User.Eco2")
		(25 "Edge.Cuts" user "Board Geometry/Outline")
		(27 "Margin" user)
		(31 "F.CrtYd" user "Package Geometry/Place Bound Top")
		(29 "B.CrtYd" user "Package Geometry/Place Bound Bottom")
		(35 "F.Fab" user "Ref Des/Assembly Top")
		(33 "B.Fab" user "Ref Des/Assembly Bottom")
	)
	(footprint ""
		(layer "F.Cu")
		(at 394.589 -85.0265 180)
		(property "Reference" "R2U11"
			(at 0 0 180)
			(layer "F.SilkS")
			(hide yes)
			(effects
				(font
					(size 1.27 1.27)
				)
			)
		)
		(property "Value" ""
			(at 0 0 180)
			(layer "F.Fab")
			(effects
				(font
					(size 1.27 1.27)
				)
			)
		)
		(duplicate_pad_numbers_are_jumpers no)
		(fp_poly
			(pts
				(xy -0.2794 -0.1016) (xy 0.2794 -0.1016) (xy 0.2794 0.9906) (xy -0.2794 0.9906)
			)
			(stroke
				(width 0)
				(type default)
			)
			(fill no)
			(layer "F.CrtYd")
		)
		(fp_line
			(start 0.2794 0.9906)
			(end 0.2794 -0.1016)
			(stroke
				(width 0.1)
				(type default)
			)
			(layer "F.Fab")
		)
		(fp_line
			(start 0.2794 -0.1016)
			(end -0.2794 -0.1016)
			(stroke
				(width 0.1)
				(type default)
			)
			(layer "F.Fab")
		)
		(fp_line
			(start -0.2794 0.9906)
			(end 0.2794 0.9906)
			(stroke
				(width 0.1)
				(type default)
			)
			(layer "F.Fab")
		)
		(fp_line
			(start -0.2794 -0.1016)
			(end -0.2794 0.9906)
			(stroke
				(width 0.1)
				(type default)
			)
			(layer "F.Fab")
		)
		(pad "1" smd rect
			(at 0 0 180)
			(size 0.508 0.508)
			(layers "F.Cu" "F.Mask" "F.Paste")
			(net "P3V3_STBY")
		)
		(pad "2" smd rect
			(at 0 0.889 180)
			(size 0.508 0.508)
			(layers "F.Cu" "F.Mask" "F.Paste")
			(net "SMB_LAN_STBY_LVC3_SDA")
		)
		(zone
			(layer "F.Cu")
			(hatch none 0.5)
			(connect_pads
				(clearance 0)
			)
			(min_thickness 0.25)
			(keepout
				(tracks not_allowed)
				(vias allowed)
				(pads allowed)
				(copperpour not_allowed)
				(footprints allowed)
			)
			(placement
				(enabled no)
				(sheetname "")
			)
			(fill
				(thermal_gap 0.5)
				(thermal_bridge_width 0.5)
				(island_removal_mode 0)
			)
			(polygon
				(pts
					(xy 394.843 -85.6615) (xy 394.335 -85.6615) (xy 394.335 -85.2805) (xy 394.843 -85.2805)
				)
			)
		)
		(zone
			(layer "F.Cu")
			(hatch none 0.5)
			(connect_pads
				(clearance 0)
			)
			(min_thickness 0.25)
			(keepout
				(tracks allowed)
				(vias not_allowed)
				(pads allowed)
				(copperpour not_allowed)
				(footprints allowed)
			)
			(placement
				(enabled no)
				(sheetname "")
			)
			(fill
				(thermal_gap 0.5)
				(thermal_bridge_width 0.5)
				(island_removal_mode 0)
			)
			(polygon
				(pts
					(xy 394.843 -85.2805) (xy 394.335 -85.2805) (xy 394.335 -85.6615) (xy 394.843 -85.6615)
				)
			)
		)
	)
	(footprint ""
		(layer "F.Cu")
		(at 166.116 -86.868 180)
		(property "Reference" "R4D2"
			(at 0 0 180)
			(layer "F.SilkS")
			(hide yes)
			(effects
				(font
					(size 1.27 1.27)
				)
			)
		)
		(property "Value" ""
			(at 0 0 180)
			(layer "F.Fab")
			(effects
				(font
					(size 1.27 1.27)
				)
			)
		)
		(duplicate_pad_numbers_are_jumpers no)
		(fp_poly
			(pts
				(xy -0.2794 -0.1016) (xy 0.2794 -0.1016) (xy 0.2794 0.9906) (xy -0.2794 0.9906)
			)
			(stroke
				(width 0)
				(type default)
			)
			(fill no)
			(layer "F.CrtYd")
		)
		(fp_line
			(start 0.2794 0.9906)
			(end 0.2794 -0.1016)
			(stroke
				(width 0.1)
				(type default)
			)
			(layer "F.Fab")
		)
		(fp_line
			(start 0.2794 -0.1016)
			(end -0.2794 -0.1016)
			(stroke
				(width 0.1)
				(type default)
			)
			(layer "F.Fab")
		)
		(fp_line
			(start -0.2794 0.9906)
			(end 0.2794 0.9906)
			(stroke
				(width 0.1)
				(type default)
			)
			(layer "F.Fab")
		)
		(fp_line
			(start -0.2794 -0.1016)
			(end -0.2794 0.9906)
			(stroke
				(width 0.1)
				(type default)
			)
			(layer "F.Fab")
		)
		(pad "1" smd rect
			(at 0 0 180)
			(size 0.508 0.508)
			(layers "F.Cu" "F.Mask" "F.Paste")
			(net "CLK_100M_CPU1_BCLK1_R_DP")
		)
		(pad "2" smd rect
			(at 0 0.889 180)
			(size 0.508 0.508)
			(layers "F.Cu" "F.Mask" "F.Paste")
			(net "CLK_100M_CPU1_BCLK1_DP")
		)
		(zone
			(layer "F.Cu")
			(hatch none 0.5)
			(connect_pads
				(clearance 0)
			)
			(min_thickness 0.25)
			(keepout
				(tracks not_allowed)
				(vias allowed)
				(pads allowed)
				(copperpour not_allowed)
				(footprints allowed)
			)
			(placement
				(enabled no)
				(sheetname "")
			)
			(fill
				(thermal_gap 0.5)
				(thermal_bridge_width 0.5)
				(island_removal_mode 0)
			)
			(polygon
				(pts
					(xy 166.37 -87.503) (xy 165.862 -87.503) (xy 165.862 -87.122) (xy 166.37 -87.122)
				)
			)
		)
		(zone
			(layer "F.Cu")
			(hatch none 0.5)
			(connect_pads
				(clearance 0)
			)
			(min_thickness 0.25)
			(keepout
				(tracks allowed)
				(vias not_allowed)
				(pads allowed)
				(copperpour not_allowed)
				(footprints allowed)
			)
			(placement
				(enabled no)
				(sheetname "")
			)
			(fill
				(thermal_gap 0.5)
				(thermal_bridge_width 0.5)
				(island_removal_mode 0)
			)
			(polygon
				(pts
					(xy 166.37 -87.122) (xy 165.862 -87.122) (xy 165.862 -87.503) (xy 166.37 -87.503)
				)
			)
		)
	)
	(footprint ""
		(layer "F.Cu")
		(at 80.757268 -149.8092 -90)
		(property "Reference" "C2A1"
			(at 1.848866 0.752348 270)
			(unlocked yes)
			(layer "F.SilkS")
			(effects
				(font
					(size 1.27 0.9652)
					(thickness 0.1524)
				)
			)
		)
		(property "Value" ""
			(at 0 0 270)
			(layer "F.Fab")
			(effects
				(font
					(size 1.27 1.27)
				)
			)
		)
		(duplicate_pad_numbers_are_jumpers no)
		(fp_rect
			(start -0.500126 1.598422)
			(end 0.500126 -0.201422)
			(stroke
				(width 0)
				(type default)
			)
			(fill no)
			(layer "F.CrtYd")
		)
		(fp_line
			(start -0.500126 1.598422)
			(end -0.500126 -0.201422)
			(stroke
				(width 0.1)
				(type default)
			)
			(layer "F.Fab")
		)
		(fp_line
			(start 0.500126 1.598422)
			(end -0.500126 1.598422)
			(stroke
				(width 0.1)
				(type default)
			)
			(layer "F.Fab")
		)
		(fp_line
			(start -0.500126 -0.201422)
			(end 0.500126 -0.201422)
			(stroke
				(width 0.1)
				(type default)
			)
			(layer "F.Fab")
		)
		(fp_line
			(start 0.500126 -0.201422)
			(end 0.500126 1.598422)
			(stroke
				(width 0.1)
				(type default)
			)
			(layer "F.Fab")
		)
		(pad "1" smd rect
			(at 0 0 180)
			(size 0.889 0.9906)
			(layers "F.Cu" "F.Mask" "F.Paste")
			(net "PVDDQ_KLM")
		)
		(pad "2" smd rect
			(at 0 1.397 180)
			(size 0.889 0.9906)
			(layers "F.Cu" "F.Mask" "F.Paste")
			(net "GND")
		)
		(zone
			(layer "F.Cu")
			(hatch none 0.5)
			(connect_pads
				(clearance 0)
			)
			(min_thickness 0.25)
			(keepout
				(tracks not_allowed)
				(vias allowed)
				(pads allowed)
				(copperpour not_allowed)
				(footprints allowed)
			)
			(placement
				(enabled no)
				(sheetname "")
			)
			(fill
				(thermal_gap 0.5)
				(thermal_bridge_width 0.5)
				(island_removal_mode 0)
			)
			(polygon
				(pts
					(xy 79.804768 -150.3045) (xy 79.804768 -149.3139) (xy 80.312768 -149.3139) (xy 80.312768 -150.3045)
				)
			)
		)
		(zone
			(layer "F.Cu")
			(hatch none 0.5)
			(connect_pads
				(clearance 0)
			)
			(min_thickness 0.25)
			(keepout
				(tracks allowed)
				(vias not_allowed)
				(pads allowed)
				(copperpour not_allowed)
				(footprints allowed)
			)
			(placement
				(enabled no)
				(sheetname "")
			)
			(fill
				(thermal_gap 0.5)
				(thermal_bridge_width 0.5)
				(island_removal_mode 0)
			)
			(polygon
				(pts
					(xy 79.804768 -150.3045) (xy 79.804768 -149.3139) (xy 80.312768 -149.3139) (xy 80.312768 -150.3045)
				)
			)
		)
	)
)
